# S9S_MB_2U (Grand Teton) — schematic netlist excerpt (pin names and nets, part order shuffled) for the footprints in the layout excerpt that follows; sources: Cadence DE-HDL packaged netlist, KiCad conversion of 03242023_DA0F0TMBIJ0_F0T_Motherboard_J_brd_V01_OCP.brd

R2310  Q_RES  10K 1% EMPTY  pkg 0402LF  page 236 : A = P3V3_AUX ; B = PCA9543_S3M_ADDR0
R3732  Q_RES  2.2K 5% CHIP  pkg 0402LF  page 233 : A = P3V3_AUX ; B = SMB_LM75_3_3V3AUX_SDA

(kicad_pcb
	(version 20260206)
	(generator "pcbnew")
	(generator_version "10.0")
	(general
		(thickness 1.6)
		(legacy_teardrops no)
	)
	(paper "A4")
	(title_block
		(title "03242023_DA0F0TMBIJ0_F0T_Motherboard_J_brd_V01_OCP.brd")
		(comment 1 "Grand Teton / footprints 3033-3034 of 6105")
	)
	(layers
		(0 "F.Cu" signal "TOP")
		(4 "In1.Cu" signal "GND")
		(6 "In2.Cu" signal "IN1")
		(8 "In3.Cu" signal "GND1")
		(10 "In4.Cu" signal "IN2")
		(12 "In5.Cu" signal "GND2")
		(14 "In6.Cu" signal "IN3")
		(16 "In7.Cu" signal "GND3")
		(18 "In8.Cu" signal "VCC")
		(20 "In9.Cu" signal "VCC1")
		(22 "In10.Cu" signal "GND4")
		(24 "In11.Cu" signal "IN4")
		(26 "In12.Cu" signal "GND5")
		(28 "In13.Cu" signal "IN5")
		(30 "In14.Cu" signal "GND6")
		(32 "In15.Cu" signal "IN6")
		(34 "In16.Cu" signal "GND7")
		(2 "B.Cu" signal "BOTTOM")
		(9 "F.Adhes" user "F.Adhesive")
		(11 "B.Adhes" user "B.Adhesive")
		(13 "F.Paste" user "Package Geometry/Pastemask Top")
		(15 "B.Paste" user "Package Geometry/Pastemask Bottom")
		(5 "F.SilkS" user "Ref Des/Silkscreen Top")
		(7 "B.SilkS" user "Ref Des/Silkscreen Bottom")
		(1 "F.Mask" user "Board Geometry/Soldermask Top")
		(3 "B.Mask" user "Board Geometry/Soldermask Bottom")
		(17 "Dwgs.User" user "User.Drawings")
		(19 "Cmts.User" user "User.Comments")
		(21 "Eco1.User" user "User.Eco1")
		(23 "Eco2.User" user "User.Eco2")
		(25 "Edge.Cuts" user "Board Geometry/Outline")
		(27 "Margin" user)
		(31 "F.CrtYd" user "Package Geometry/Place Bound Top")
		(29 "B.CrtYd" user "Package Geometry/Place Bound Bottom")
		(35 "F.Fab" user "Ref Des/Assembly Top")
		(33 "B.Fab" user "Ref Des/Assembly Bottom")
	)
	(footprint ""
		(layer "F.Cu")
		(at 155.98013 -70.26402 90)
		(property "Reference" "R2310"
			(at 0 0 90)
			(layer "F.SilkS")
			(hide yes)
			(effects
				(font
					(size 1.27 1.27)
				)
			)
		)
		(property "Value" ""
			(at 0 0 90)
			(layer "F.Fab")
			(effects
				(font
					(size 1.27 1.27)
				)
			)
		)
		(duplicate_pad_numbers_are_jumpers no)
		(fp_line
			(start 0.7874 -0.4064)
			(end 0.7874 0.4064)
			(stroke
				(width 0.1524)
				(type default)
			)
			(layer "F.SilkS")
		)
		(fp_line
			(start -0.7874 -0.4064)
			(end 0.7874 -0.4064)
			(stroke
				(width 0.1524)
				(type default)
			)
			(layer "F.SilkS")
		)
		(fp_line
			(start 0.7874 0.4064)
			(end -0.7874 0.4064)
			(stroke
				(width 0.1524)
				(type default)
			)
			(layer "F.SilkS")
		)
		(fp_line
			(start -0.7874 0.4064)
			(end -0.7874 -0.4064)
			(stroke
				(width 0.1524)
				(type default)
			)
			(layer "F.SilkS")
		)
		(fp_line
			(start -0.12065 -0.305054)
			(end -0.12065 -0.2794)
			(stroke
				(width 0.1)
				(type default)
			)
			(layer "F.Fab")
		)
		(fp_line
			(start -0.67945 -0.305054)
			(end -0.12065 -0.305054)
			(stroke
				(width 0.1)
				(type default)
			)
			(layer "F.Fab")
		)
		(fp_line
			(start 0.67945 -0.3048)
			(end 0.67945 0.3048)
			(stroke
				(width 0.1)
				(type default)
			)
			(layer "F.Fab")
		)
		(fp_line
			(start 0.12065 -0.3048)
			(end 0.67945 -0.3048)
			(stroke
				(width 0.1)
				(type default)
			)
			(layer "F.Fab")
		)
		(fp_line
			(start 0.12065 -0.2794)
			(end 0.12065 -0.3048)
			(stroke
				(width 0.1)
				(type default)
			)
			(layer "F.Fab")
		)
		(fp_line
			(start -0.12065 -0.2794)
			(end 0.12065 -0.2794)
			(stroke
				(width 0.1)
				(type default)
			)
			(layer "F.Fab")
		)
		(fp_line
			(start 0.120396 0.2794)
			(end -0.12065 0.2794)
			(stroke
				(width 0.1)
				(type default)
			)
			(layer "F.Fab")
		)
		(fp_line
			(start -0.12065 0.2794)
			(end -0.12065 0.3048)
			(stroke
				(width 0.1)
				(type default)
			)
			(layer "F.Fab")
		)
		(fp_line
			(start 0.67945 0.3048)
			(end 0.120396 0.3048)
			(stroke
				(width 0.1)
				(type default)
			)
			(layer "F.Fab")
		)
		(fp_line
			(start 0.120396 0.3048)
			(end 0.120396 0.2794)
			(stroke
				(width 0.1)
				(type default)
			)
			(layer "F.Fab")
		)
		(fp_line
			(start -0.12065 0.3048)
			(end -0.67945 0.3048)
			(stroke
				(width 0.1)
				(type default)
			)
			(layer "F.Fab")
		)
		(fp_line
			(start -0.67945 0.3048)
			(end -0.67945 -0.305054)
			(stroke
				(width 0.1)
				(type default)
			)
			(layer "F.Fab")
		)
		(pad "1" smd circle
			(at -0.40005 0 90)
			(size 0 0)
			(layers "F.Cu" "F.Mask" "F.Paste")
			(net "P3V3_AUX")
		)
		(pad "2" smd circle
			(at 0.40005 0 90)
			(size 0 0)
			(layers "F.Cu" "F.Mask" "F.Paste")
			(net "PCA9543_S3M_ADDR0")
		)
	)
	(footprint ""
		(layer "F.Cu")
		(at 68.081144 -106.319066)
		(property "Reference" "R3732"
			(at 0 0 0)
			(layer "F.SilkS")
			(hide yes)
			(effects
				(font
					(size 1.27 1.27)
				)
			)
		)
		(property "Value" ""
			(at 0 0 0)
			(layer "F.Fab")
			(effects
				(font
					(size 1.27 1.27)
				)
			)
		)
		(duplicate_pad_numbers_are_jumpers no)
		(fp_line
			(start -0.7874 -0.4064)
			(end 0.7874 -0.4064)
			(stroke
				(width 0.1524)
				(type default)
			)
			(layer "F.SilkS")
		)
		(fp_line
			(start -0.7874 0.4064)
			(end -0.7874 -0.4064)
			(stroke
				(width 0.1524)
				(type default)
			)
			(layer "F.SilkS")
		)
		(fp_line
			(start 0.7874 -0.4064)
			(end 0.7874 0.4064)
			(stroke
				(width 0.1524)
				(type default)
			)
			(layer "F.SilkS")
		)
		(fp_line
			(start 0.7874 0.4064)
			(end -0.7874 0.4064)
			(stroke
				(width 0.1524)
				(type default)
			)
			(layer "F.SilkS")
		)
		(fp_line
			(start -0.67945 -0.305054)
			(end -0.12065 -0.305054)
			(stroke
				(width 0.1)
				(type default)
			)
			(layer "F.Fab")
		)
		(fp_line
			(start -0.67945 0.3048)
			(end -0.67945 -0.305054)
			(stroke
				(width 0.1)
				(type default)
			)
			(layer "F.Fab")
		)
		(fp_line
			(start -0.12065 -0.305054)
			(end -0.12065 -0.2794)
			(stroke
				(width 0.1)
				(type default)
			)
			(layer "F.Fab")
		)
		(fp_line
			(start -0.12065 -0.2794)
			(end 0.12065 -0.2794)
			(stroke
				(width 0.1)
				(type default)
			)
			(layer "F.Fab")
		)
		(fp_line
			(start -0.12065 0.2794)
			(end -0.12065 0.3048)
			(stroke
				(width 0.1)
				(type default)
			)
			(layer "F.Fab")
		)
		(fp_line
			(start -0.12065 0.3048)
			(end -0.67945 0.3048)
			(stroke
				(width 0.1)
				(type default)
			)
			(layer "F.Fab")
		)
		(fp_line
			(start 0.120396 0.2794)
			(end -0.12065 0.2794)
			(stroke
				(width 0.1)
				(type default)
			)
			(layer "F.Fab")
		)
		(fp_line
			(start 0.120396 0.3048)
			(end 0.120396 0.2794)
			(stroke
				(width 0.1)
				(type default)
			)
			(layer "F.Fab")
		)
		(fp_line
			(start 0.12065 -0.3048)
			(end 0.67945 -0.3048)
			(stroke
				(width 0.1)
				(type default)
			)
			(layer "F.Fab")
		)
		(fp_line
			(start 0.12065 -0.2794)
			(end 0.12065 -0.3048)
			(stroke
				(width 0.1)
				(type default)
			)
			(layer "F.Fab")
		)
		(fp_line
			(start 0.67945 -0.3048)
			(end 0.67945 0.3048)
			(stroke
				(width 0.1)
				(type default)
			)
			(layer "F.Fab")
		)
		(fp_line
			(start 0.67945 0.3048)
			(end 0.120396 0.3048)
			(stroke
				(width 0.1)
				(type default)
			)
			(layer "F.Fab")
		)
		(pad "1" smd circle
			(at -0.40005 0)
			(size 0 0)
			(layers "F.Cu" "F.Mask" "F.Paste")
			(net "P3V3_AUX")
		)
		(pad "2" smd circle
			(at 0.40005 0)
			(size 0 0)
			(layers "F.Cu" "F.Mask" "F.Paste")
			(net "SMB_LM75_3_3V3AUX_SDA")
		)
	)
)
